(kicad_pcb
	(version 20260206)
	(generator "pcbnew")
	(generator_version "10.0")
	(general
		(thickness 1.6)
		(legacy_teardrops no)
	)
	(paper "A4")
	(title_block
		(title "03242023_DA0F0TMBIJ0_F0T_Motherboard_J_brd_V01_OCP.brd")
		(comment 1 "Grand Teton / footprints 4129-4133 of 6105")
	)
	(layers
		(0 "F.Cu" signal "TOP")
		(4 "In1.Cu" signal "GND")
		(6 "In2.Cu" signal "IN1")
		(8 "In3.Cu" signal "GND1")
		(10 "In4.Cu" signal "IN2")
		(12 "In5.Cu" signal "GND2")
		(14 "In6.Cu" signal "IN3")
		(16 "In7.Cu" signal "GND3")
		(18 "In8.Cu" signal "VCC")
		(20 "In9.Cu" signal "VCC1")
		(22 "In10.Cu" signal "GND4")
		(24 "In11.Cu" signal "IN4")
		(26 "In12.Cu" signal "GND5")
		(28 "In13.Cu" signal "IN5")
		(30 "In14.Cu" signal "GND6")
		(32 "In15.Cu" signal "IN6")
		(34 "In16.Cu" signal "GND7")
		(2 "B.Cu" signal "BOTTOM")
		(9 "F.Adhes" user "F.Adhesive")
		(11 "B.Adhes" user "B.Adhesive")
		(13 "F.Paste" user "Package Geometry/Pastemask Top")
		(15 "B.Paste" user "Package Geometry/Pastemask Bottom")
		(5 "F.SilkS" user "Ref Des/Silkscreen Top")
		(7 "B.SilkS" user "Ref Des/Silkscreen Bottom")
		(1 "F.Mask" user "Board Geometry/Soldermask Top")
		(3 "B.Mask" user "Board Geometry/Soldermask Bottom")
		(17 "Dwgs.User" user "User.Drawings")
		(19 "Cmts.User" user "User.Comments")
		(21 "Eco1.User" user "User.Eco1")
		(23 "Eco2.User" user "User.Eco2")
		(25 "Edge.Cuts" user "Board Geometry/Outline")
		(27 "Margin" user)
		(31 "F.CrtYd" user "Package Geometry/Place Bound Top")
		(29 "B.CrtYd" user "Package Geometry/Place Bound Bottom")
		(35 "F.Fab" user "Ref Des/Assembly Top")
		(33 "B.Fab" user "Ref Des/Assembly Bottom")
	)
	(footprint ""
		(layer "F.Cu")
		(at 39.194232 -131.897374 180)
		(property "Reference" "R2354"
			(at 0 0 180)
			(layer "F.SilkS")
			(hide yes)
			(effects
				(font
					(size 1.27 1.27)
				)
			)
		)
		(property "Value" ""
			(at 0 0 180)
			(layer "F.Fab")
			(effects
				(font
					(size 1.27 1.27)
				)
			)
		)
		(duplicate_pad_numbers_are_jumpers no)
		(fp_line
			(start 0.7874 0.4064)
			(end -0.7874 0.4064)
			(stroke
				(width 0.1524)
				(type default)
			)
			(layer "F.SilkS")
		)
		(fp_line
			(start 0.7874 -0.4064)
			(end 0.7874 0.4064)
			(stroke
				(width 0.1524)
				(type default)
			)
			(layer "F.SilkS")
		)
		(fp_line
			(start -0.7874 0.4064)
			(end -0.7874 -0.4064)
			(stroke
				(width 0.1524)
				(type default)
			)
			(layer "F.SilkS")
		)
		(fp_line
			(start -0.7874 -0.4064)
			(end 0.7874 -0.4064)
			(stroke
				(width 0.1524)
				(type default)
			)
			(layer "F.SilkS")
		)
		(fp_line
			(start 0.67945 0.3048)
			(end 0.120396 0.3048)
			(stroke
				(width 0.1)
				(type default)
			)
			(layer "F.Fab")
		)
		(fp_line
			(start 0.67945 -0.3048)
			(end 0.67945 0.3048)
			(stroke
				(width 0.1)
				(type default)
			)
			(layer "F.Fab")
		)
		(fp_line
			(start 0.12065 -0.2794)
			(end 0.12065 -0.3048)
			(stroke
				(width 0.1)
				(type default)
			)
			(layer "F.Fab")
		)
		(fp_line
			(start 0.12065 -0.3048)
			(end 0.67945 -0.3048)
			(stroke
				(width 0.1)
				(type default)
			)
			(layer "F.Fab")
		)
		(fp_line
			(start 0.120396 0.3048)
			(end 0.120396 0.2794)
			(stroke
				(width 0.1)
				(type default)
			)
			(layer "F.Fab")
		)
		(fp_line
			(start 0.120396 0.2794)
			(end -0.12065 0.2794)
			(stroke
				(width 0.1)
				(type default)
			)
			(layer "F.Fab")
		)
		(fp_line
			(start -0.12065 0.3048)
			(end -0.67945 0.3048)
			(stroke
				(width 0.1)
				(type default)
			)
			(layer "F.Fab")
		)
		(fp_line
			(start -0.12065 0.2794)
			(end -0.12065 0.3048)
			(stroke
				(width 0.1)
				(type default)
			)
			(layer "F.Fab")
		)
		(fp_line
			(start -0.12065 -0.2794)
			(end 0.12065 -0.2794)
			(stroke
				(width 0.1)
				(type default)
			)
			(layer "F.Fab")
		)
		(fp_line
			(start -0.12065 -0.305054)
			(end -0.12065 -0.2794)
			(stroke
				(width 0.1)
				(type default)
			)
			(layer "F.Fab")
		)
		(fp_line
			(start -0.67945 0.3048)
			(end -0.67945 -0.305054)
			(stroke
				(width 0.1)
				(type default)
			)
			(layer "F.Fab")
		)
		(fp_line
			(start -0.67945 -0.305054)
			(end -0.12065 -0.305054)
			(stroke
				(width 0.1)
				(type default)
			)
			(layer "F.Fab")
		)
		(pad "1" smd circle
			(at -0.40005 0 180)
			(size 0 0)
			(layers "F.Cu" "F.Mask" "F.Paste")
			(net "PVNN_TERM_CPU1")
		)
		(pad "2" smd circle
			(at 0.40005 0 180)
			(size 0 0)
			(layers "F.Cu" "F.Mask" "F.Paste")
			(net "SVID_DIO0_CPU1_R")
		)
	)
	(footprint ""
		(layer "F.Cu")
		(at 49.300638 -408.517344 -90)
		(property "Reference" "C708"
			(at 0 0 270)
			(layer "F.SilkS")
			(hide yes)
			(effects
				(font
					(size 1.27 1.27)
				)
			)
		)
		(property "Value" ""
			(at 0 0 270)
			(layer "F.Fab")
			(effects
				(font
					(size 1.27 1.27)
				)
			)
		)
		(duplicate_pad_numbers_are_jumpers no)
		(fp_line
			(start -0.299974 0.150114)
			(end -0.299974 -0.150114)
			(stroke
				(width 0.1)
				(type default)
			)
			(layer "F.Fab")
		)
		(fp_line
			(start 0.299974 0.150114)
			(end -0.299974 0.150114)
			(stroke
				(width 0.1)
				(type default)
			)
			(layer "F.Fab")
		)
		(fp_line
			(start -0.299974 -0.150114)
			(end 0.299974 -0.150114)
			(stroke
				(width 0.1)
				(type default)
			)
			(layer "F.Fab")
		)
		(fp_line
			(start 0.299974 -0.150114)
			(end 0.299974 0.150114)
			(stroke
				(width 0.1)
				(type default)
			)
			(layer "F.Fab")
		)
		(pad "1" smd rect
			(at -0.2667 0 270)
			(size 0.3048 0.381)
			(layers "F.Cu" "F.Mask" "F.Paste")
			(net "P5E_CPU1_PE4_TX_C_DN<0>")
		)
		(pad "2" smd rect
			(at 0.2667 0 270)
			(size 0.3048 0.381)
			(layers "F.Cu" "F.Mask" "F.Paste")
			(net "P5E_CPU1_PE4_TX_DN<0>")
		)
	)
	(footprint ""
		(layer "F.Cu")
		(at 370.905278 -423.232326 -90)
		(property "Reference" "U270"
			(at -0.413512 -2.776982 0)
			(unlocked yes)
			(layer "F.SilkS")
			(effects
				(font
					(size 0.7874 0.5842)
					(thickness 0.1524)
				)
				(justify left)
			)
		)
		(property "Value" ""
			(at 0 0 270)
			(layer "F.Fab")
			(effects
				(font
					(size 1.27 1.27)
				)
			)
		)
		(duplicate_pad_numbers_are_jumpers no)
		(fp_line
			(start -3.447796 2.500122)
			(end 3.447796 2.500122)
			(stroke
				(width 0.1524)
				(type default)
			)
			(layer "F.SilkS")
		)
		(fp_line
			(start 3.447796 2.500122)
			(end 3.447796 -2.500122)
			(stroke
				(width 0.1524)
				(type default)
			)
			(layer "F.SilkS")
		)
		(fp_line
			(start 0 -1.016)
			(end -1.484122 -2.500122)
			(stroke
				(width 0.1524)
				(type default)
			)
			(layer "F.SilkS")
		)
		(fp_line
			(start -3.447796 -2.500122)
			(end -3.447796 2.500122)
			(stroke
				(width 0.1524)
				(type default)
			)
			(layer "F.SilkS")
		)
		(fp_line
			(start -1.484122 -2.500122)
			(end -3.447796 -2.500122)
			(stroke
				(width 0.1524)
				(type default)
			)
			(layer "F.SilkS")
		)
		(fp_line
			(start 1.484122 -2.500122)
			(end 0 -1.016)
			(stroke
				(width 0.1524)
				(type default)
			)
			(layer "F.SilkS")
		)
		(fp_line
			(start 3.447796 -2.500122)
			(end 1.484122 -2.500122)
			(stroke
				(width 0.1524)
				(type default)
			)
			(layer "F.SilkS")
		)
		(fp_poly
			(pts
				(xy -4.260342 -2.232914) (xy -3.60426 -1.905) (xy -4.260342 -1.577086)
			)
			(stroke
				(width 0)
				(type default)
			)
			(fill yes)
			(layer "F.SilkS")
		)
		(fp_line
			(start -1.999996 2.500122)
			(end 1.999996 2.500122)
			(stroke
				(width 0.1)
				(type default)
			)
			(layer "F.Fab")
		)
		(fp_line
			(start 1.999996 2.500122)
			(end 1.999996 -2.500122)
			(stroke
				(width 0.1)
				(type default)
			)
			(layer "F.Fab")
		)
		(fp_line
			(start -1.999996 -2.500122)
			(end -1.999996 2.500122)
			(stroke
				(width 0.1)
				(type default)
			)
			(layer "F.Fab")
		)
		(fp_line
			(start 1.999996 -2.500122)
			(end -1.999996 -2.500122)
			(stroke
				(width 0.1)
				(type default)
			)
			(layer "F.Fab")
		)
		(fp_poly
			(pts
				(xy -4.5974 -2.413) (xy -4.5974 -1.397) (xy -3.5814 -1.905)
			)
			(stroke
				(width 0)
				(type default)
			)
			(fill yes)
			(layer "F.Fab")
		)
		(pad "1" smd rect
			(at -2.649982 -1.905 180)
			(size 0.6096 1.3208)
			(layers "F.Cu" "F.Mask" "F.Paste")
			(net "SMB_LM75_0_3V3AUX_SDA_R1")
		)
		(pad "2" smd rect
			(at -2.649982 -0.635 180)
			(size 0.6096 1.3208)
			(layers "F.Cu" "F.Mask" "F.Paste")
			(net "SMB_LM75_0_3V3AUX_SCL_R1")
		)
		(pad "3" smd rect
			(at -2.649982 0.635 180)
			(size 0.6096 1.3208)
			(layers "F.Cu" "F.Mask" "F.Paste")
			(net "FM_G751_0_ALERT_N")
		)
		(pad "4" smd rect
			(at -2.649982 1.905 180)
			(size 0.6096 1.3208)
			(layers "F.Cu" "F.Mask" "F.Paste")
			(net "GND")
		)
		(pad "5" smd rect
			(at 2.649982 1.905 180)
			(size 0.6096 1.3208)
			(layers "F.Cu" "F.Mask" "F.Paste")
			(net "U270_0_ADD2")
		)
		(pad "6" smd rect
			(at 2.649982 0.635 180)
			(size 0.6096 1.3208)
			(layers "F.Cu" "F.Mask" "F.Paste")
			(net "U270_0_ADD1")
		)
		(pad "7" smd rect
			(at 2.649982 -0.635 180)
			(size 0.6096 1.3208)
			(layers "F.Cu" "F.Mask" "F.Paste")
			(net "U270_0_ADD0")
		)
		(pad "8" smd rect
			(at 2.649982 -1.905 180)
			(size 0.6096 1.3208)
			(layers "F.Cu" "F.Mask" "F.Paste")
			(net "P3V3_AUX")
		)
	)
	(footprint ""
		(layer "F.Cu")
		(at 445.19088 -95.872808 180)
		(property "Reference" "R3601"
			(at 0 0 180)
			(layer "F.SilkS")
			(hide yes)
			(effects
				(font
					(size 1.27 1.27)
				)
			)
		)
		(property "Value" ""
			(at 0 0 180)
			(layer "F.Fab")
			(effects
				(font
					(size 1.27 1.27)
				)
			)
		)
		(duplicate_pad_numbers_are_jumpers no)
		(fp_line
			(start 0.7874 0.4064)
			(end -0.7874 0.4064)
			(stroke
				(width 0.1524)
				(type default)
			)
			(layer "F.SilkS")
		)
		(fp_line
			(start 0.7874 -0.4064)
			(end 0.7874 0.4064)
			(stroke
				(width 0.1524)
				(type default)
			)
			(layer "F.SilkS")
		)
		(fp_line
			(start -0.7874 0.4064)
			(end -0.7874 -0.4064)
			(stroke
				(width 0.1524)
				(type default)
			)
			(layer "F.SilkS")
		)
		(fp_line
			(start -0.7874 -0.4064)
			(end 0.7874 -0.4064)
			(stroke
				(width 0.1524)
				(type default)
			)
			(layer "F.SilkS")
		)
		(fp_line
			(start 0.67945 0.3048)
			(end 0.120396 0.3048)
			(stroke
				(width 0.1)
				(type default)
			)
			(layer "F.Fab")
		)
		(fp_line
			(start 0.67945 -0.3048)
			(end 0.67945 0.3048)
			(stroke
				(width 0.1)
				(type default)
			)
			(layer "F.Fab")
		)
		(fp_line
			(start 0.12065 -0.2794)
			(end 0.12065 -0.3048)
			(stroke
				(width 0.1)
				(type default)
			)
			(layer "F.Fab")
		)
		(fp_line
			(start 0.12065 -0.3048)
			(end 0.67945 -0.3048)
			(stroke
				(width 0.1)
				(type default)
			)
			(layer "F.Fab")
		)
		(fp_line
			(start 0.120396 0.3048)
			(end 0.120396 0.2794)
			(stroke
				(width 0.1)
				(type default)
			)
			(layer "F.Fab")
		)
		(fp_line
			(start 0.120396 0.2794)
			(end -0.12065 0.2794)
			(stroke
				(width 0.1)
				(type default)
			)
			(layer "F.Fab")
		)
		(fp_line
			(start -0.12065 0.3048)
			(end -0.67945 0.3048)
			(stroke
				(width 0.1)
				(type default)
			)
			(layer "F.Fab")
		)
		(fp_line
			(start -0.12065 0.2794)
			(end -0.12065 0.3048)
			(stroke
				(width 0.1)
				(type default)
			)
			(layer "F.Fab")
		)
		(fp_line
			(start -0.12065 -0.2794)
			(end 0.12065 -0.2794)
			(stroke
				(width 0.1)
				(type default)
			)
			(layer "F.Fab")
		)
		(fp_line
			(start -0.12065 -0.305054)
			(end -0.12065 -0.2794)
			(stroke
				(width 0.1)
				(type default)
			)
			(layer "F.Fab")
		)
		(fp_line
			(start -0.67945 0.3048)
			(end -0.67945 -0.305054)
			(stroke
				(width 0.1)
				(type default)
			)
			(layer "F.Fab")
		)
		(fp_line
			(start -0.67945 -0.305054)
			(end -0.12065 -0.305054)
			(stroke
				(width 0.1)
				(type default)
			)
			(layer "F.Fab")
		)
		(pad "1" smd circle
			(at -0.40005 0 180)
			(size 0 0)
			(layers "F.Cu" "F.Mask" "F.Paste")
			(net "SMB_INA230_1_3V3AUX_SDA_R")
		)
		(pad "2" smd circle
			(at 0.40005 0 180)
			(size 0 0)
			(layers "F.Cu" "F.Mask" "F.Paste")
			(net "SMB_INA230_1_3V3AUX_SDA_R1")
		)
	)
	(footprint ""
		(layer "F.Cu")
		(at 431.828956 -105.32745 -90)
		(property "Reference" "PU202"
			(at 3.334004 -1.70815 0)
			(unlocked yes)
			(layer "F.SilkS")
			(effects
				(font
					(size 0.7874 0.5842)
					(thickness 0.1524)
				)
				(justify left)
			)
		)
		(property "Value" ""
			(at 0 0 270)
			(layer "F.Fab")
			(effects
				(font
					(size 1.27 1.27)
				)
			)
		)
		(duplicate_pad_numbers_are_jumpers no)
		(fp_line
			(start -1.774952 1.039876)
			(end 1.774952 1.039876)
			(stroke
				(width 0.1524)
				(type default)
			)
			(layer "F.SilkS")
		)
		(fp_line
			(start 1.774952 1.039876)
			(end 1.774952 -1.039876)
			(stroke
				(width 0.1524)
				(type default)
			)
			(layer "F.SilkS")
		)
		(fp_line
			(start -1.774952 -1.039876)
			(end -1.774952 1.039876)
			(stroke
				(width 0.1524)
				(type default)
			)
			(layer "F.SilkS")
		)
		(fp_line
			(start 1.774952 -1.039876)
			(end -1.774952 -1.039876)
			(stroke
				(width 0.1524)
				(type default)
			)
			(layer "F.SilkS")
		)
		(fp_poly
			(pts
				(xy -1.769872 -1.039876) (xy -1.769872 -0.249936) (xy -2.531872 -0.249936) (xy -2.531872 -1.801876)
				(xy -0.999998 -1.801876) (xy -0.999998 -1.039876)
			)
			(stroke
				(width 0)
				(type default)
			)
			(fill yes)
			(layer "F.SilkS")
		)
		(fp_line
			(start -1.769872 1.039876)
			(end 1.769872 1.039876)
			(stroke
				(width 0.1)
				(type default)
			)
			(layer "F.Fab")
		)
		(fp_line
			(start 1.769872 1.039876)
			(end 1.769872 -1.039876)
			(stroke
				(width 0.1)
				(type default)
			)
			(layer "F.Fab")
		)
		(fp_line
			(start -1.769872 -1.039876)
			(end -1.769872 1.039876)
			(stroke
				(width 0.1)
				(type default)
			)
			(layer "F.Fab")
		)
		(fp_line
			(start 1.769872 -1.039876)
			(end -1.769872 -1.039876)
			(stroke
				(width 0.1)
				(type default)
			)
			(layer "F.Fab")
		)
		(fp_poly
			(pts
				(xy -1.769872 -1.039876) (xy -0.999998 -1.039876) (xy -0.999998 -1.801876) (xy -2.531872 -1.801876)
				(xy -2.531872 -0.249936) (xy -1.769872 -0.249936)
			)
			(stroke
				(width 0)
				(type default)
			)
			(fill yes)
			(layer "F.Fab")
		)
		(pad "A1" smd circle
			(at -1.500124 -0.750062 270)
			(size 0.2286 0.2286)
			(layers "F.Cu" "F.Mask" "F.Paste")
			(net "P3V3_OCP_SENSE_1")
		)
		(pad "A2" smd circle
			(at -0.999998 -0.750062 270)
			(size 0.2286 0.2286)
			(layers "F.Cu" "F.Mask" "F.Paste")
			(net "P3V3_OCP_VCC_1")
		)
		(pad "A3" smd circle
			(at -0.499872 -0.750062 270)
			(size 0.2286 0.2286)
			(layers "F.Cu" "F.Mask" "F.Paste")
			(net "P3V3_AUX")
		)
		(pad "A4" smd circle
			(at 0 -0.750062 270)
			(size 0.2286 0.2286)
			(layers "F.Cu" "F.Mask" "F.Paste")
			(net "P3V3_OCP_SFF_R")
		)
		(pad "A5" smd circle
			(at 0.499872 -0.750062 270)
			(size 0.2286 0.2286)
			(layers "F.Cu" "F.Mask" "F.Paste")
			(net "P3V3_AUX")
		)
		(pad "A6" smd circle
			(at 0.999998 -0.750062 270)
			(size 0.2286 0.2286)
			(layers "F.Cu" "F.Mask" "F.Paste")
			(net "P3V3_OCP_GATE_PU202_1")
		)
		(pad "A7" smd circle
			(at 1.500124 -0.750062 270)
			(size 0.2286 0.2286)
			(layers "F.Cu" "F.Mask" "F.Paste")
			(net "GND")
		)
		(pad "B1" smd circle
			(at -1.500124 -0.249936 270)
			(size 0.2286 0.2286)
			(layers "F.Cu" "F.Mask" "F.Paste")
			(net "P3V3_OCP_CB_1")
		)
		(pad "B2" smd circle
			(at -0.999998 -0.249936 270)
			(size 0.2286 0.2286)
			(layers "F.Cu" "F.Mask" "F.Paste")
			(net "GND")
		)
		(pad "B3" smd circle
			(at -0.499872 -0.249936 270)
			(size 0.2286 0.2286)
			(layers "F.Cu" "F.Mask" "F.Paste")
			(net "P3V3_AUX")
		)
		(pad "B4" smd circle
			(at 0 -0.249936 270)
			(size 0.2286 0.2286)
			(layers "F.Cu" "F.Mask" "F.Paste")
			(net "P3V3_OCP_SFF_R")
		)
		(pad "B5" smd circle
			(at 0.499872 -0.249936 270)
			(size 0.2286 0.2286)
			(layers "F.Cu" "F.Mask" "F.Paste")
			(net "P3V3_AUX")
		)
		(pad "B6" smd circle
			(at 0.999998 -0.249936 270)
			(size 0.2286 0.2286)
			(layers "F.Cu" "F.Mask" "F.Paste")
			(net "P3V3_OCP_SFF_R")
		)
		(pad "B7" smd circle
			(at 1.500124 -0.249936 270)
			(size 0.2286 0.2286)
			(layers "F.Cu" "F.Mask" "F.Paste")
			(net "GND")
		)
		(pad "C1" smd circle
			(at -1.500124 0.249936 270)
			(size 0.2286 0.2286)
			(layers "F.Cu" "F.Mask" "F.Paste")
			(net "GND")
		)
		(pad "C2" smd circle
			(at -0.999998 0.249936 270)
			(size 0.2286 0.2286)
			(layers "F.Cu" "F.Mask" "F.Paste")
			(net "GND")
		)
		(pad "C3" smd circle
			(at -0.499872 0.249936 270)
			(size 0.2286 0.2286)
			(layers "F.Cu" "F.Mask" "F.Paste")
			(net "P3V3_AUX")
		)
		(pad "C4" smd circle
			(at 0 0.249936 270)
			(size 0.2286 0.2286)
			(layers "F.Cu" "F.Mask" "F.Paste")
			(net "P3V3_OCP_SFF_R")
		)
		(pad "C5" smd circle
			(at 0.499872 0.249936 270)
			(size 0.2286 0.2286)
			(layers "F.Cu" "F.Mask" "F.Paste")
			(net "P3V3_AUX")
		)
		(pad "C6" smd circle
			(at 0.999998 0.249936 270)
			(size 0.2286 0.2286)
			(layers "F.Cu" "F.Mask" "F.Paste")
			(net "P3V3_OCP_SFF_R")
		)
		(pad "C7" smd circle
			(at 1.500124 0.249936 270)
			(size 0.2286 0.2286)
			(layers "F.Cu" "F.Mask" "F.Paste")
			(net "P3V3_OCP_FAULT_1")
		)
		(pad "D1" smd circle
			(at -1.500124 0.750062 270)
			(size 0.2286 0.2286)
			(layers "F.Cu" "F.Mask" "F.Paste")
			(net "P3V3_OCP_REG_1")
		)
		(pad "D2" smd circle
			(at -0.999998 0.750062 270)
			(size 0.2286 0.2286)
			(layers "F.Cu" "F.Mask" "F.Paste")
			(net "P3V3_OCP_UV_1")
		)
		(pad "D3" smd circle
			(at -0.499872 0.750062 270)
			(size 0.2286 0.2286)
			(layers "F.Cu" "F.Mask" "F.Paste")
			(net "P3V3_OCP_OV_1")
		)
		(pad "D4" smd circle
			(at 0 0.750062 270)
			(size 0.2286 0.2286)
			(layers "F.Cu" "F.Mask" "F.Paste")
			(net "P3V3_OCP_SFF_R")
		)
		(pad "D5" smd circle
			(at 0.499872 0.750062 270)
			(size 0.2286 0.2286)
			(layers "F.Cu" "F.Mask" "F.Paste")
			(net "P3V3_AUX")
		)
		(pad "D6" smd circle
			(at 0.999998 0.750062 270)
			(size 0.2286 0.2286)
			(layers "F.Cu" "F.Mask" "F.Paste")
			(net "P3V3_OCP_SFF_R")
		)
		(pad "D7" smd circle
			(at 1.500124 0.750062 270)
			(size 0.2286 0.2286)
			(layers "F.Cu" "F.Mask" "F.Paste")
			(net "P3V3_OCP_PWRGD_1")
		)
	)
)
